(kicad_pcb
	(version 20260206)
	(generator "pcbnew")
	(generator_version "10.0")
	(general
		(thickness 1.6)
		(legacy_teardrops no)
	)
	(paper "A4")
	(title_block
		(title "04192023_DAF0TMB3IC0_F0TG_MB_C_brd_V02_OCP.brd")
		(comment 1 "Grand Teton / footprints 3592-3598 of 8354")
	)
	(layers
		(0 "F.Cu" signal "TOP")
		(4 "In1.Cu" signal "GND")
		(6 "In2.Cu" signal "IN1")
		(8 "In3.Cu" signal "GND1")
		(10 "In4.Cu" signal "IN2")
		(12 "In5.Cu" signal "GND2")
		(14 "In6.Cu" signal "IN3")
		(16 "In7.Cu" signal "GND3")
		(18 "In8.Cu" signal "VCC")
		(20 "In9.Cu" signal "VCC1")
		(22 "In10.Cu" signal "GND4")
		(24 "In11.Cu" signal "IN4")
		(26 "In12.Cu" signal "GND5")
		(28 "In13.Cu" signal "IN5")
		(30 "In14.Cu" signal "GND6")
		(32 "In15.Cu" signal "IN6")
		(34 "In16.Cu" signal "GND7")
		(2 "B.Cu" signal "BOTTOM")
		(9 "F.Adhes" user "F.Adhesive")
		(11 "B.Adhes" user "B.Adhesive")
		(13 "F.Paste" user "Package Geometry/Pastemask Top")
		(15 "B.Paste" user "Package Geometry/Pastemask Bottom")
		(5 "F.SilkS" user "Ref Des/Silkscreen Top")
		(7 "B.SilkS" user "Ref Des/Silkscreen Bottom")
		(1 "F.Mask" user "Board Geometry/Soldermask Top")
		(3 "B.Mask" user "Board Geometry/Soldermask Bottom")
		(17 "Dwgs.User" user "User.Drawings")
		(19 "Cmts.User" user "User.Comments")
		(21 "Eco1.User" user "User.Eco1")
		(23 "Eco2.User" user "User.Eco2")
		(25 "Edge.Cuts" user "Board Geometry/Outline")
		(27 "Margin" user)
		(31 "F.CrtYd" user "Package Geometry/Place Bound Top")
		(29 "B.CrtYd" user "Package Geometry/Place Bound Bottom")
		(35 "F.Fab" user "Ref Des/Assembly Top")
		(33 "B.Fab" user "Ref Des/Assembly Bottom")
	)
	(footprint ""
		(layer "F.Cu")
		(at 68.212462 -38.405562 180)
		(property "Reference" "R3620"
			(at 0 0 180)
			(layer "F.SilkS")
			(hide yes)
			(effects
				(font
					(size 1.27 1.27)
				)
			)
		)
		(property "Value" ""
			(at 0 0 180)
			(layer "F.Fab")
			(effects
				(font
					(size 1.27 1.27)
				)
			)
		)
		(duplicate_pad_numbers_are_jumpers no)
		(fp_line
			(start 0.7874 0.4064)
			(end -0.7874 0.4064)
			(stroke
				(width 0.1524)
				(type default)
			)
			(layer "F.SilkS")
		)
		(fp_line
			(start 0.7874 -0.4064)
			(end 0.7874 0.4064)
			(stroke
				(width 0.1524)
				(type default)
			)
			(layer "F.SilkS")
		)
		(fp_line
			(start -0.7874 0.4064)
			(end -0.7874 -0.4064)
			(stroke
				(width 0.1524)
				(type default)
			)
			(layer "F.SilkS")
		)
		(fp_line
			(start -0.7874 -0.4064)
			(end 0.7874 -0.4064)
			(stroke
				(width 0.1524)
				(type default)
			)
			(layer "F.SilkS")
		)
		(fp_line
			(start 0.67945 0.3048)
			(end 0.120396 0.3048)
			(stroke
				(width 0.1)
				(type default)
			)
			(layer "F.Fab")
		)
		(fp_line
			(start 0.67945 -0.3048)
			(end 0.67945 0.3048)
			(stroke
				(width 0.1)
				(type default)
			)
			(layer "F.Fab")
		)
		(fp_line
			(start 0.12065 -0.2794)
			(end 0.12065 -0.3048)
			(stroke
				(width 0.1)
				(type default)
			)
			(layer "F.Fab")
		)
		(fp_line
			(start 0.12065 -0.3048)
			(end 0.67945 -0.3048)
			(stroke
				(width 0.1)
				(type default)
			)
			(layer "F.Fab")
		)
		(fp_line
			(start 0.120396 0.3048)
			(end 0.120396 0.2794)
			(stroke
				(width 0.1)
				(type default)
			)
			(layer "F.Fab")
		)
		(fp_line
			(start 0.120396 0.2794)
			(end -0.12065 0.2794)
			(stroke
				(width 0.1)
				(type default)
			)
			(layer "F.Fab")
		)
		(fp_line
			(start -0.12065 0.3048)
			(end -0.67945 0.3048)
			(stroke
				(width 0.1)
				(type default)
			)
			(layer "F.Fab")
		)
		(fp_line
			(start -0.12065 0.2794)
			(end -0.12065 0.3048)
			(stroke
				(width 0.1)
				(type default)
			)
			(layer "F.Fab")
		)
		(fp_line
			(start -0.12065 -0.2794)
			(end 0.12065 -0.2794)
			(stroke
				(width 0.1)
				(type default)
			)
			(layer "F.Fab")
		)
		(fp_line
			(start -0.12065 -0.305054)
			(end -0.12065 -0.2794)
			(stroke
				(width 0.1)
				(type default)
			)
			(layer "F.Fab")
		)
		(fp_line
			(start -0.67945 0.3048)
			(end -0.67945 -0.305054)
			(stroke
				(width 0.1)
				(type default)
			)
			(layer "F.Fab")
		)
		(fp_line
			(start -0.67945 -0.305054)
			(end -0.12065 -0.305054)
			(stroke
				(width 0.1)
				(type default)
			)
			(layer "F.Fab")
		)
		(pad "1" smd circle
			(at -0.40005 0 180)
			(size 0 0)
			(layers "F.Cu" "F.Mask" "F.Paste")
			(net "INA230_3_A0")
		)
		(pad "2" smd circle
			(at 0.40005 0 180)
			(size 0 0)
			(layers "F.Cu" "F.Mask" "F.Paste")
			(net "SMB_INA230_3_3V3AUX_SCL_R1")
		)
	)
	(footprint ""
		(layer "F.Cu")
		(at 185.322464 -426.405294 -90)
		(property "Reference" "R3518"
			(at 0 0 270)
			(layer "F.SilkS")
			(hide yes)
			(effects
				(font
					(size 1.27 1.27)
				)
			)
		)
		(property "Value" ""
			(at 0 0 270)
			(layer "F.Fab")
			(effects
				(font
					(size 1.27 1.27)
				)
			)
		)
		(duplicate_pad_numbers_are_jumpers no)
		(fp_line
			(start -0.7874 0.4064)
			(end -0.7874 -0.4064)
			(stroke
				(width 0.1524)
				(type default)
			)
			(layer "F.SilkS")
		)
		(fp_line
			(start 0.7874 0.4064)
			(end -0.7874 0.4064)
			(stroke
				(width 0.1524)
				(type default)
			)
			(layer "F.SilkS")
		)
		(fp_line
			(start -0.7874 -0.4064)
			(end 0.7874 -0.4064)
			(stroke
				(width 0.1524)
				(type default)
			)
			(layer "F.SilkS")
		)
		(fp_line
			(start 0.7874 -0.4064)
			(end 0.7874 0.4064)
			(stroke
				(width 0.1524)
				(type default)
			)
			(layer "F.SilkS")
		)
		(fp_line
			(start -0.67945 0.3048)
			(end -0.67945 -0.305054)
			(stroke
				(width 0.1)
				(type default)
			)
			(layer "F.Fab")
		)
		(fp_line
			(start -0.12065 0.3048)
			(end -0.67945 0.3048)
			(stroke
				(width 0.1)
				(type default)
			)
			(layer "F.Fab")
		)
		(fp_line
			(start 0.120396 0.3048)
			(end 0.120396 0.2794)
			(stroke
				(width 0.1)
				(type default)
			)
			(layer "F.Fab")
		)
		(fp_line
			(start 0.67945 0.3048)
			(end 0.120396 0.3048)
			(stroke
				(width 0.1)
				(type default)
			)
			(layer "F.Fab")
		)
		(fp_line
			(start -0.12065 0.2794)
			(end -0.12065 0.3048)
			(stroke
				(width 0.1)
				(type default)
			)
			(layer "F.Fab")
		)
		(fp_line
			(start 0.120396 0.2794)
			(end -0.12065 0.2794)
			(stroke
				(width 0.1)
				(type default)
			)
			(layer "F.Fab")
		)
		(fp_line
			(start -0.12065 -0.2794)
			(end 0.12065 -0.2794)
			(stroke
				(width 0.1)
				(type default)
			)
			(layer "F.Fab")
		)
		(fp_line
			(start 0.12065 -0.2794)
			(end 0.12065 -0.3048)
			(stroke
				(width 0.1)
				(type default)
			)
			(layer "F.Fab")
		)
		(fp_line
			(start 0.12065 -0.3048)
			(end 0.67945 -0.3048)
			(stroke
				(width 0.1)
				(type default)
			)
			(layer "F.Fab")
		)
		(fp_line
			(start 0.67945 -0.3048)
			(end 0.67945 0.3048)
			(stroke
				(width 0.1)
				(type default)
			)
			(layer "F.Fab")
		)
		(fp_line
			(start -0.67945 -0.305054)
			(end -0.12065 -0.305054)
			(stroke
				(width 0.1)
				(type default)
			)
			(layer "F.Fab")
		)
		(fp_line
			(start -0.12065 -0.305054)
			(end -0.12065 -0.2794)
			(stroke
				(width 0.1)
				(type default)
			)
			(layer "F.Fab")
		)
		(pad "1" smd circle
			(at -0.40005 0 270)
			(size 0 0)
			(layers "F.Cu" "F.Mask" "F.Paste")
			(net "GPU_PEX_STRAP0")
		)
		(pad "2" smd circle
			(at 0.40005 0 270)
			(size 0 0)
			(layers "F.Cu" "F.Mask" "F.Paste")
			(net "GPU_PEX_STRAP0_R")
		)
	)
	(footprint ""
		(layer "F.Cu")
		(at 102.87 -426.466 90)
		(property "Reference" "R3489"
			(at 0 0 90)
			(layer "F.SilkS")
			(hide yes)
			(effects
				(font
					(size 1.27 1.27)
				)
			)
		)
		(property "Value" ""
			(at 0 0 90)
			(layer "F.Fab")
			(effects
				(font
					(size 1.27 1.27)
				)
			)
		)
		(duplicate_pad_numbers_are_jumpers no)
		(fp_line
			(start 0.7874 -0.4064)
			(end 0.7874 0.4064)
			(stroke
				(width 0.1524)
				(type default)
			)
			(layer "F.SilkS")
		)
		(fp_line
			(start -0.7874 -0.4064)
			(end 0.7874 -0.4064)
			(stroke
				(width 0.1524)
				(type default)
			)
			(layer "F.SilkS")
		)
		(fp_line
			(start 0.7874 0.4064)
			(end -0.7874 0.4064)
			(stroke
				(width 0.1524)
				(type default)
			)
			(layer "F.SilkS")
		)
		(fp_line
			(start -0.7874 0.4064)
			(end -0.7874 -0.4064)
			(stroke
				(width 0.1524)
				(type default)
			)
			(layer "F.SilkS")
		)
		(fp_line
			(start -0.12065 -0.305054)
			(end -0.12065 -0.2794)
			(stroke
				(width 0.1)
				(type default)
			)
			(layer "F.Fab")
		)
		(fp_line
			(start -0.67945 -0.305054)
			(end -0.12065 -0.305054)
			(stroke
				(width 0.1)
				(type default)
			)
			(layer "F.Fab")
		)
		(fp_line
			(start 0.67945 -0.3048)
			(end 0.67945 0.3048)
			(stroke
				(width 0.1)
				(type default)
			)
			(layer "F.Fab")
		)
		(fp_line
			(start 0.12065 -0.3048)
			(end 0.67945 -0.3048)
			(stroke
				(width 0.1)
				(type default)
			)
			(layer "F.Fab")
		)
		(fp_line
			(start 0.12065 -0.2794)
			(end 0.12065 -0.3048)
			(stroke
				(width 0.1)
				(type default)
			)
			(layer "F.Fab")
		)
		(fp_line
			(start -0.12065 -0.2794)
			(end 0.12065 -0.2794)
			(stroke
				(width 0.1)
				(type default)
			)
			(layer "F.Fab")
		)
		(fp_line
			(start 0.120396 0.2794)
			(end -0.12065 0.2794)
			(stroke
				(width 0.1)
				(type default)
			)
			(layer "F.Fab")
		)
		(fp_line
			(start -0.12065 0.2794)
			(end -0.12065 0.3048)
			(stroke
				(width 0.1)
				(type default)
			)
			(layer "F.Fab")
		)
		(fp_line
			(start 0.67945 0.3048)
			(end 0.120396 0.3048)
			(stroke
				(width 0.1)
				(type default)
			)
			(layer "F.Fab")
		)
		(fp_line
			(start 0.120396 0.3048)
			(end 0.120396 0.2794)
			(stroke
				(width 0.1)
				(type default)
			)
			(layer "F.Fab")
		)
		(fp_line
			(start -0.12065 0.3048)
			(end -0.67945 0.3048)
			(stroke
				(width 0.1)
				(type default)
			)
			(layer "F.Fab")
		)
		(fp_line
			(start -0.67945 0.3048)
			(end -0.67945 -0.305054)
			(stroke
				(width 0.1)
				(type default)
			)
			(layer "F.Fab")
		)
		(pad "1" smd circle
			(at -0.40005 0 90)
			(size 0 0)
			(layers "F.Cu" "F.Mask" "F.Paste")
			(net "GPU_FPGA_EROT_RST_N")
		)
		(pad "2" smd circle
			(at 0.40005 0 90)
			(size 0 0)
			(layers "F.Cu" "F.Mask" "F.Paste")
			(net "GND")
		)
	)
	(footprint ""
		(layer "F.Cu")
		(at 366.06734 -390.77646 180)
		(property "Reference" "C901"
			(at 0 0 180)
			(layer "F.SilkS")
			(hide yes)
			(effects
				(font
					(size 1.27 1.27)
				)
			)
		)
		(property "Value" ""
			(at 0 0 180)
			(layer "F.Fab")
			(effects
				(font
					(size 1.27 1.27)
				)
			)
		)
		(duplicate_pad_numbers_are_jumpers no)
		(fp_line
			(start 0.299974 0.150114)
			(end -0.299974 0.150114)
			(stroke
				(width 0.1)
				(type default)
			)
			(layer "F.Fab")
		)
		(fp_line
			(start 0.299974 -0.150114)
			(end 0.299974 0.150114)
			(stroke
				(width 0.1)
				(type default)
			)
			(layer "F.Fab")
		)
		(fp_line
			(start -0.299974 0.150114)
			(end -0.299974 -0.150114)
			(stroke
				(width 0.1)
				(type default)
			)
			(layer "F.Fab")
		)
		(fp_line
			(start -0.299974 -0.150114)
			(end 0.299974 -0.150114)
			(stroke
				(width 0.1)
				(type default)
			)
			(layer "F.Fab")
		)
		(pad "1" smd rect
			(at -0.2667 0 180)
			(size 0.3048 0.381)
			(layers "F.Cu" "F.Mask" "F.Paste")
			(net "P5E_CPU0_P3_TX_C_DP<0>")
		)
		(pad "2" smd rect
			(at 0.2667 0 180)
			(size 0.3048 0.381)
			(layers "F.Cu" "F.Mask" "F.Paste")
			(net "P5E_CPU0_P3_TX_DP<0>")
		)
	)
	(footprint ""
		(layer "F.Cu")
		(at 52.23891 -351.932748)
		(property "Reference" "PR275"
			(at 0 0 0)
			(layer "F.SilkS")
			(hide yes)
			(effects
				(font
					(size 1.27 1.27)
				)
			)
		)
		(property "Value" ""
			(at 0 0 0)
			(layer "F.Fab")
			(effects
				(font
					(size 1.27 1.27)
				)
			)
		)
		(duplicate_pad_numbers_are_jumpers no)
		(fp_line
			(start -0.7874 -0.4064)
			(end 0.7874 -0.4064)
			(stroke
				(width 0.1524)
				(type default)
			)
			(layer "F.SilkS")
		)
		(fp_line
			(start -0.7874 0.4064)
			(end -0.7874 -0.4064)
			(stroke
				(width 0.1524)
				(type default)
			)
			(layer "F.SilkS")
		)
		(fp_line
			(start 0.7874 -0.4064)
			(end 0.7874 0.4064)
			(stroke
				(width 0.1524)
				(type default)
			)
			(layer "F.SilkS")
		)
		(fp_line
			(start 0.7874 0.4064)
			(end -0.7874 0.4064)
			(stroke
				(width 0.1524)
				(type default)
			)
			(layer "F.SilkS")
		)
		(fp_line
			(start -0.67945 -0.305054)
			(end -0.12065 -0.305054)
			(stroke
				(width 0.1)
				(type default)
			)
			(layer "F.Fab")
		)
		(fp_line
			(start -0.67945 0.3048)
			(end -0.67945 -0.305054)
			(stroke
				(width 0.1)
				(type default)
			)
			(layer "F.Fab")
		)
		(fp_line
			(start -0.12065 -0.305054)
			(end -0.12065 -0.2794)
			(stroke
				(width 0.1)
				(type default)
			)
			(layer "F.Fab")
		)
		(fp_line
			(start -0.12065 -0.2794)
			(end 0.12065 -0.2794)
			(stroke
				(width 0.1)
				(type default)
			)
			(layer "F.Fab")
		)
		(fp_line
			(start -0.12065 0.2794)
			(end -0.12065 0.3048)
			(stroke
				(width 0.1)
				(type default)
			)
			(layer "F.Fab")
		)
		(fp_line
			(start -0.12065 0.3048)
			(end -0.67945 0.3048)
			(stroke
				(width 0.1)
				(type default)
			)
			(layer "F.Fab")
		)
		(fp_line
			(start 0.120396 0.2794)
			(end -0.12065 0.2794)
			(stroke
				(width 0.1)
				(type default)
			)
			(layer "F.Fab")
		)
		(fp_line
			(start 0.120396 0.3048)
			(end 0.120396 0.2794)
			(stroke
				(width 0.1)
				(type default)
			)
			(layer "F.Fab")
		)
		(fp_line
			(start 0.12065 -0.3048)
			(end 0.67945 -0.3048)
			(stroke
				(width 0.1)
				(type default)
			)
			(layer "F.Fab")
		)
		(fp_line
			(start 0.12065 -0.2794)
			(end 0.12065 -0.3048)
			(stroke
				(width 0.1)
				(type default)
			)
			(layer "F.Fab")
		)
		(fp_line
			(start 0.67945 -0.3048)
			(end 0.67945 0.3048)
			(stroke
				(width 0.1)
				(type default)
			)
			(layer "F.Fab")
		)
		(fp_line
			(start 0.67945 0.3048)
			(end 0.120396 0.3048)
			(stroke
				(width 0.1)
				(type default)
			)
			(layer "F.Fab")
		)
		(pad "1" smd circle
			(at -0.40005 0)
			(size 0 0)
			(layers "F.Cu" "F.Mask" "F.Paste")
			(net "PVDDIO_P1_LSET1")
		)
		(pad "2" smd circle
			(at 0.40005 0)
			(size 0 0)
			(layers "F.Cu" "F.Mask" "F.Paste")
			(net "GND")
		)
	)
	(footprint ""
		(layer "F.Cu")
		(at 426.469556 -397.135604 180)
		(property "Reference" "R1046"
			(at 0 0 180)
			(layer "F.SilkS")
			(hide yes)
			(effects
				(font
					(size 1.27 1.27)
				)
			)
		)
		(property "Value" ""
			(at 0 0 180)
			(layer "F.Fab")
			(effects
				(font
					(size 1.27 1.27)
				)
			)
		)
		(duplicate_pad_numbers_are_jumpers no)
		(fp_line
			(start 0.7874 0.4064)
			(end -0.7874 0.4064)
			(stroke
				(width 0.1524)
				(type default)
			)
			(layer "F.SilkS")
		)
		(fp_line
			(start 0.7874 -0.4064)
			(end 0.7874 0.4064)
			(stroke
				(width 0.1524)
				(type default)
			)
			(layer "F.SilkS")
		)
		(fp_line
			(start -0.7874 0.4064)
			(end -0.7874 -0.4064)
			(stroke
				(width 0.1524)
				(type default)
			)
			(layer "F.SilkS")
		)
		(fp_line
			(start -0.7874 -0.4064)
			(end 0.7874 -0.4064)
			(stroke
				(width 0.1524)
				(type default)
			)
			(layer "F.SilkS")
		)
		(fp_line
			(start 0.67945 0.3048)
			(end 0.120396 0.3048)
			(stroke
				(width 0.1)
				(type default)
			)
			(layer "F.Fab")
		)
		(fp_line
			(start 0.67945 -0.3048)
			(end 0.67945 0.3048)
			(stroke
				(width 0.1)
				(type default)
			)
			(layer "F.Fab")
		)
		(fp_line
			(start 0.12065 -0.2794)
			(end 0.12065 -0.3048)
			(stroke
				(width 0.1)
				(type default)
			)
			(layer "F.Fab")
		)
		(fp_line
			(start 0.12065 -0.3048)
			(end 0.67945 -0.3048)
			(stroke
				(width 0.1)
				(type default)
			)
			(layer "F.Fab")
		)
		(fp_line
			(start 0.120396 0.3048)
			(end 0.120396 0.2794)
			(stroke
				(width 0.1)
				(type default)
			)
			(layer "F.Fab")
		)
		(fp_line
			(start 0.120396 0.2794)
			(end -0.12065 0.2794)
			(stroke
				(width 0.1)
				(type default)
			)
			(layer "F.Fab")
		)
		(fp_line
			(start -0.12065 0.3048)
			(end -0.67945 0.3048)
			(stroke
				(width 0.1)
				(type default)
			)
			(layer "F.Fab")
		)
		(fp_line
			(start -0.12065 0.2794)
			(end -0.12065 0.3048)
			(stroke
				(width 0.1)
				(type default)
			)
			(layer "F.Fab")
		)
		(fp_line
			(start -0.12065 -0.2794)
			(end 0.12065 -0.2794)
			(stroke
				(width 0.1)
				(type default)
			)
			(layer "F.Fab")
		)
		(fp_line
			(start -0.12065 -0.305054)
			(end -0.12065 -0.2794)
			(stroke
				(width 0.1)
				(type default)
			)
			(layer "F.Fab")
		)
		(fp_line
			(start -0.67945 0.3048)
			(end -0.67945 -0.305054)
			(stroke
				(width 0.1)
				(type default)
			)
			(layer "F.Fab")
		)
		(fp_line
			(start -0.67945 -0.305054)
			(end -0.12065 -0.305054)
			(stroke
				(width 0.1)
				(type default)
			)
			(layer "F.Fab")
		)
		(pad "1" smd rect
			(at -0.40005 0)
			(size 0.4572 0.508)
			(layers "F.Cu" "F.Mask" "F.Paste")
			(net "P1V8_CPU0_RT2_1A_1D")
		)
		(pad "2" smd rect
			(at 0.40005 0)
			(size 0.4572 0.508)
			(layers "F.Cu" "F.Mask" "F.Paste")
			(net "P1V8_CPU0_RT2_1A")
		)
	)
	(footprint ""
		(layer "F.Cu")
		(at 353.1108 -407.8732 90)
		(property "Reference" "R1472"
			(at 0 0 90)
			(layer "F.SilkS")
			(hide yes)
			(effects
				(font
					(size 1.27 1.27)
				)
			)
		)
		(property "Value" ""
			(at 0 0 90)
			(layer "F.Fab")
			(effects
				(font
					(size 1.27 1.27)
				)
			)
		)
		(duplicate_pad_numbers_are_jumpers no)
		(fp_line
			(start 0.32512 -0.175006)
			(end 0.32512 0.175006)
			(stroke
				(width 0.1)
				(type default)
			)
			(layer "F.Fab")
		)
		(fp_line
			(start -0.32512 -0.175006)
			(end 0.32512 -0.175006)
			(stroke
				(width 0.1)
				(type default)
			)
			(layer "F.Fab")
		)
		(fp_line
			(start 0.32512 0.175006)
			(end -0.32512 0.175006)
			(stroke
				(width 0.1)
				(type default)
			)
			(layer "F.Fab")
		)
		(fp_line
			(start -0.32512 0.175006)
			(end -0.32512 -0.175006)
			(stroke
				(width 0.1)
				(type default)
			)
			(layer "F.Fab")
		)
		(pad "1" smd rect
			(at -0.2667 0 90)
			(size 0.3048 0.381)
			(layers "F.Cu" "F.Mask" "F.Paste")
			(net "P1V8_CPU0_RT_1D")
		)
		(pad "2" smd rect
			(at 0.2667 0 270)
			(size 0.3048 0.381)
			(layers "F.Cu" "F.Mask" "F.Paste")
			(net "JTAG_TDO_RT_CPU0_P1")
		)
	)
)
